(kicad_pcb
	(version 20260206)
	(generator "pcbnew")
	(generator_version "10.0")
	(general
		(thickness 1.6)
		(legacy_teardrops no)
	)
	(paper "A4")
	(title_block
		(title "9052_F0T_PDB_Converter_Brick_F_V03_1208_1600_OCP.brd")
		(comment 1 "Grand Teton / footprints 247-254 of 578")
	)
	(layers
		(0 "F.Cu" signal "TOP")
		(4 "In1.Cu" signal "GND")
		(6 "In2.Cu" signal "IN1")
		(8 "In3.Cu" signal "GND1")
		(10 "In4.Cu" signal "VCC")
		(12 "In5.Cu" signal "VCC1")
		(14 "In6.Cu" signal "GND2")
		(16 "In7.Cu" signal "IN2")
		(18 "In8.Cu" signal "GND3")
		(2 "B.Cu" signal "BOTTOM")
		(9 "F.Adhes" user "F.Adhesive")
		(11 "B.Adhes" user "B.Adhesive")
		(13 "F.Paste" user "Package Geometry/Pastemask Top")
		(15 "B.Paste" user "Package Geometry/Pastemask Bottom")
		(5 "F.SilkS" user "Ref Des/Silkscreen Top")
		(7 "B.SilkS" user "Ref Des/Silkscreen Bottom")
		(1 "F.Mask" user "Board Geometry/Soldermask Top")
		(3 "B.Mask" user "Board Geometry/Soldermask Bottom")
		(17 "Dwgs.User" user "User.Drawings")
		(19 "Cmts.User" user "User.Comments")
		(21 "Eco1.User" user "User.Eco1")
		(23 "Eco2.User" user "User.Eco2")
		(25 "Edge.Cuts" user "Board Geometry/Outline")
		(27 "Margin" user)
		(31 "F.CrtYd" user "Package Geometry/Place Bound Top")
		(29 "B.CrtYd" user "Package Geometry/Place Bound Bottom")
		(35 "F.Fab" user "Ref Des/Assembly Top")
		(33 "B.Fab" user "Ref Des/Assembly Bottom")
	)
	(footprint ""
		(layer "F.Cu")
		(at 100.965 -51.943)
		(property "Reference" "PC66"
			(at 0 0 0)
			(layer "F.SilkS")
			(hide yes)
			(effects
				(font
					(size 1.27 1.27)
				)
			)
		)
		(property "Value" ""
			(at 0 0 0)
			(layer "F.Fab")
			(effects
				(font
					(size 1.27 1.27)
				)
			)
		)
		(duplicate_pad_numbers_are_jumpers no)
		(fp_line
			(start -1.524 -0.762)
			(end 1.524 -0.762)
			(stroke
				(width 0.1524)
				(type default)
			)
			(layer "F.SilkS")
		)
		(fp_line
			(start -1.524 0.762)
			(end -1.524 -0.762)
			(stroke
				(width 0.1524)
				(type default)
			)
			(layer "F.SilkS")
		)
		(fp_line
			(start 1.524 -0.762)
			(end 1.524 0.762)
			(stroke
				(width 0.1524)
				(type default)
			)
			(layer "F.SilkS")
		)
		(fp_line
			(start 1.524 0.762)
			(end -1.524 0.762)
			(stroke
				(width 0.1524)
				(type default)
			)
			(layer "F.SilkS")
		)
		(fp_line
			(start -1.1049 -0.724916)
			(end -1.1049 0.724916)
			(stroke
				(width 0.1)
				(type default)
			)
			(layer "F.Fab")
		)
		(fp_line
			(start -1.1049 0.724916)
			(end 1.1049 0.724916)
			(stroke
				(width 0.1)
				(type default)
			)
			(layer "F.Fab")
		)
		(fp_line
			(start 1.1049 -0.724916)
			(end -1.1049 -0.724916)
			(stroke
				(width 0.1)
				(type default)
			)
			(layer "F.Fab")
		)
		(fp_line
			(start 1.1049 0.724916)
			(end 1.1049 -0.724916)
			(stroke
				(width 0.1)
				(type default)
			)
			(layer "F.Fab")
		)
		(pad "1" smd rect
			(at -0.889 0 180)
			(size 1.016 1.27)
			(layers "F.Cu" "F.Mask" "F.Paste")
			(net "P12V_BRICK")
		)
		(pad "2" smd rect
			(at 0.889 0 180)
			(size 1.016 1.27)
			(layers "F.Cu" "F.Mask" "F.Paste")
			(net "GND")
		)
	)
	(footprint ""
		(layer "F.Cu")
		(at 205.05801 -113.24717 90)
		(property "Reference" "L5"
			(at -7.576566 -6.472174 0)
			(unlocked yes)
			(layer "F.SilkS")
			(effects
				(font
					(size 0.7874 0.5842)
					(thickness 0.1524)
				)
				(justify left)
			)
		)
		(property "Value" ""
			(at 0 0 90)
			(layer "F.Fab")
			(effects
				(font
					(size 1.27 1.27)
				)
			)
		)
		(duplicate_pad_numbers_are_jumpers no)
		(fp_line
			(start 6.849872 -6.450076)
			(end -6.849872 -6.450076)
			(stroke
				(width 0.1524)
				(type default)
			)
			(layer "F.SilkS")
		)
		(fp_line
			(start -6.849872 -6.450076)
			(end -6.849872 -2.6416)
			(stroke
				(width 0.1524)
				(type default)
			)
			(layer "F.SilkS")
		)
		(fp_line
			(start 6.849872 -2.6416)
			(end 6.849872 -6.450076)
			(stroke
				(width 0.1524)
				(type default)
			)
			(layer "F.SilkS")
		)
		(fp_line
			(start -6.849872 2.6416)
			(end -6.849872 6.450076)
			(stroke
				(width 0.1524)
				(type default)
			)
			(layer "F.SilkS")
		)
		(fp_line
			(start 6.849872 6.450076)
			(end 6.849872 2.6416)
			(stroke
				(width 0.1524)
				(type default)
			)
			(layer "F.SilkS")
		)
		(fp_line
			(start -6.849872 6.450076)
			(end 6.849872 6.450076)
			(stroke
				(width 0.1524)
				(type default)
			)
			(layer "F.SilkS")
		)
		(fp_line
			(start 6.849872 -6.450076)
			(end -6.849872 -6.450076)
			(stroke
				(width 0.1)
				(type default)
			)
			(layer "F.Fab")
		)
		(fp_line
			(start -6.849872 -6.450076)
			(end -6.849872 6.450076)
			(stroke
				(width 0.1)
				(type default)
			)
			(layer "F.Fab")
		)
		(fp_line
			(start 6.849872 6.450076)
			(end 6.849872 -6.450076)
			(stroke
				(width 0.1)
				(type default)
			)
			(layer "F.Fab")
		)
		(fp_line
			(start -6.849872 6.450076)
			(end 6.849872 6.450076)
			(stroke
				(width 0.1)
				(type default)
			)
			(layer "F.Fab")
		)
		(pad "1" smd rect
			(at -5.407406 0 90)
			(size 2.9464 5.0038)
			(layers "F.Cu" "F.Mask" "F.Paste")
			(net "P52V_HS")
		)
		(pad "2" smd rect
			(at 5.407406 0 90)
			(size 2.9464 5.0038)
			(layers "F.Cu" "F.Mask" "F.Paste")
			(net "P52V_HS_FILTER")
		)
	)
	(footprint ""
		(layer "F.Cu")
		(at 56.905906 -127.889)
		(property "Reference" "PC77"
			(at 0 0 0)
			(layer "F.SilkS")
			(hide yes)
			(effects
				(font
					(size 1.27 1.27)
				)
			)
		)
		(property "Value" ""
			(at 0 0 0)
			(layer "F.Fab")
			(effects
				(font
					(size 1.27 1.27)
				)
			)
		)
		(duplicate_pad_numbers_are_jumpers no)
		(fp_line
			(start -2.2098 -0.9398)
			(end 2.2098 -0.9398)
			(stroke
				(width 0.1524)
				(type default)
			)
			(layer "F.SilkS")
		)
		(fp_line
			(start -2.2098 0.9398)
			(end -2.2098 -0.9398)
			(stroke
				(width 0.1524)
				(type default)
			)
			(layer "F.SilkS")
		)
		(fp_line
			(start 2.2098 -0.9398)
			(end 2.2098 0.9398)
			(stroke
				(width 0.1524)
				(type default)
			)
			(layer "F.SilkS")
		)
		(fp_line
			(start 2.2098 0.9398)
			(end -2.2098 0.9398)
			(stroke
				(width 0.1524)
				(type default)
			)
			(layer "F.SilkS")
		)
		(fp_line
			(start -1.700022 -0.899922)
			(end 1.700022 -0.899922)
			(stroke
				(width 0.1)
				(type default)
			)
			(layer "F.Fab")
		)
		(fp_line
			(start -1.700022 0.899922)
			(end -1.700022 -0.899922)
			(stroke
				(width 0.1)
				(type default)
			)
			(layer "F.Fab")
		)
		(fp_line
			(start 1.700022 -0.899922)
			(end 1.700022 0.899922)
			(stroke
				(width 0.1)
				(type default)
			)
			(layer "F.Fab")
		)
		(fp_line
			(start 1.700022 0.899922)
			(end -1.700022 0.899922)
			(stroke
				(width 0.1)
				(type default)
			)
			(layer "F.Fab")
		)
		(pad "1" smd rect
			(at -1.4732 0 180)
			(size 1.1684 1.5748)
			(layers "F.Cu" "F.Mask" "F.Paste")
			(net "P52V_HS_FILTER")
		)
		(pad "2" smd rect
			(at 1.4732 0 180)
			(size 1.1684 1.5748)
			(layers "F.Cu" "F.Mask" "F.Paste")
			(net "GND")
		)
	)
	(footprint ""
		(layer "F.Cu")
		(at 176.906174 -130.175)
		(property "Reference" "PC117"
			(at 0 0 0)
			(layer "F.SilkS")
			(hide yes)
			(effects
				(font
					(size 1.27 1.27)
				)
			)
		)
		(property "Value" ""
			(at 0 0 0)
			(layer "F.Fab")
			(effects
				(font
					(size 1.27 1.27)
				)
			)
		)
		(duplicate_pad_numbers_are_jumpers no)
		(fp_line
			(start -2.2098 -0.9398)
			(end 2.2098 -0.9398)
			(stroke
				(width 0.1524)
				(type default)
			)
			(layer "F.SilkS")
		)
		(fp_line
			(start -2.2098 0.9398)
			(end -2.2098 -0.9398)
			(stroke
				(width 0.1524)
				(type default)
			)
			(layer "F.SilkS")
		)
		(fp_line
			(start 2.2098 -0.9398)
			(end 2.2098 0.9398)
			(stroke
				(width 0.1524)
				(type default)
			)
			(layer "F.SilkS")
		)
		(fp_line
			(start 2.2098 0.9398)
			(end -2.2098 0.9398)
			(stroke
				(width 0.1524)
				(type default)
			)
			(layer "F.SilkS")
		)
		(fp_line
			(start -1.700022 -0.899922)
			(end 1.700022 -0.899922)
			(stroke
				(width 0.1)
				(type default)
			)
			(layer "F.Fab")
		)
		(fp_line
			(start -1.700022 0.899922)
			(end -1.700022 -0.899922)
			(stroke
				(width 0.1)
				(type default)
			)
			(layer "F.Fab")
		)
		(fp_line
			(start 1.700022 -0.899922)
			(end 1.700022 0.899922)
			(stroke
				(width 0.1)
				(type default)
			)
			(layer "F.Fab")
		)
		(fp_line
			(start 1.700022 0.899922)
			(end -1.700022 0.899922)
			(stroke
				(width 0.1)
				(type default)
			)
			(layer "F.Fab")
		)
		(pad "1" smd rect
			(at -1.4732 0 180)
			(size 1.1684 1.5748)
			(layers "F.Cu" "F.Mask" "F.Paste")
			(net "P52V_HS_FILTER")
		)
		(pad "2" smd rect
			(at 1.4732 0 180)
			(size 1.1684 1.5748)
			(layers "F.Cu" "F.Mask" "F.Paste")
			(net "GND")
		)
	)
	(footprint ""
		(layer "F.Cu")
		(at 191.643 -6.985)
		(property "Reference" "PC104"
			(at 0 0 0)
			(layer "F.SilkS")
			(hide yes)
			(effects
				(font
					(size 1.27 1.27)
				)
			)
		)
		(property "Value" ""
			(at 0 0 0)
			(layer "F.Fab")
			(effects
				(font
					(size 1.27 1.27)
				)
			)
		)
		(duplicate_pad_numbers_are_jumpers no)
		(fp_line
			(start -0.7874 -0.4064)
			(end 0.7874 -0.4064)
			(stroke
				(width 0.1524)
				(type default)
			)
			(layer "F.SilkS")
		)
		(fp_line
			(start -0.7874 0.4064)
			(end -0.7874 -0.4064)
			(stroke
				(width 0.1524)
				(type default)
			)
			(layer "F.SilkS")
		)
		(fp_line
			(start 0.7874 -0.4064)
			(end 0.7874 0.4064)
			(stroke
				(width 0.1524)
				(type default)
			)
			(layer "F.SilkS")
		)
		(fp_line
			(start 0.7874 0.4064)
			(end -0.7874 0.4064)
			(stroke
				(width 0.1524)
				(type default)
			)
			(layer "F.SilkS")
		)
		(fp_line
			(start -0.67945 -0.305054)
			(end -0.12065 -0.305054)
			(stroke
				(width 0.1)
				(type default)
			)
			(layer "F.Fab")
		)
		(fp_line
			(start -0.67945 0.3048)
			(end -0.67945 -0.305054)
			(stroke
				(width 0.1)
				(type default)
			)
			(layer "F.Fab")
		)
		(fp_line
			(start -0.12065 -0.305054)
			(end -0.12065 -0.2794)
			(stroke
				(width 0.1)
				(type default)
			)
			(layer "F.Fab")
		)
		(fp_line
			(start -0.12065 -0.2794)
			(end 0.12065 -0.2794)
			(stroke
				(width 0.1)
				(type default)
			)
			(layer "F.Fab")
		)
		(fp_line
			(start -0.12065 0.2794)
			(end -0.12065 0.3048)
			(stroke
				(width 0.1)
				(type default)
			)
			(layer "F.Fab")
		)
		(fp_line
			(start -0.12065 0.3048)
			(end -0.67945 0.3048)
			(stroke
				(width 0.1)
				(type default)
			)
			(layer "F.Fab")
		)
		(fp_line
			(start 0.120396 0.2794)
			(end -0.12065 0.2794)
			(stroke
				(width 0.1)
				(type default)
			)
			(layer "F.Fab")
		)
		(fp_line
			(start 0.120396 0.3048)
			(end 0.120396 0.2794)
			(stroke
				(width 0.1)
				(type default)
			)
			(layer "F.Fab")
		)
		(fp_line
			(start 0.12065 -0.3048)
			(end 0.67945 -0.3048)
			(stroke
				(width 0.1)
				(type default)
			)
			(layer "F.Fab")
		)
		(fp_line
			(start 0.12065 -0.2794)
			(end 0.12065 -0.3048)
			(stroke
				(width 0.1)
				(type default)
			)
			(layer "F.Fab")
		)
		(fp_line
			(start 0.67945 -0.3048)
			(end 0.67945 0.3048)
			(stroke
				(width 0.1)
				(type default)
			)
			(layer "F.Fab")
		)
		(fp_line
			(start 0.67945 0.3048)
			(end 0.120396 0.3048)
			(stroke
				(width 0.1)
				(type default)
			)
			(layer "F.Fab")
		)
		(pad "1" smd circle
			(at -0.40005 0)
			(size 0 0)
			(layers "F.Cu" "F.Mask" "F.Paste")
			(net "P3V3_AUX")
		)
		(pad "2" smd circle
			(at 0.40005 0)
			(size 0 0)
			(layers "F.Cu" "F.Mask" "F.Paste")
			(net "GND")
		)
	)
	(footprint ""
		(layer "F.Cu")
		(at 292.354 -22.9616 90)
		(property "Reference" "JP3"
			(at 2.13233 -1.27 0)
			(unlocked yes)
			(layer "F.SilkS")
			(effects
				(font
					(size 0.7874 0.5842)
					(thickness 0.1524)
				)
				(justify left)
			)
		)
		(property "Value" ""
			(at 0 0 90)
			(layer "F.Fab")
			(effects
				(font
					(size 1.27 1.27)
				)
			)
		)
		(duplicate_pad_numbers_are_jumpers no)
		(fp_line
			(start 1.234948 -1.335024)
			(end 1.234948 6.415024)
			(stroke
				(width 0.1524)
				(type default)
			)
			(layer "F.SilkS")
		)
		(fp_line
			(start -1.234948 -1.335024)
			(end 1.234948 -1.335024)
			(stroke
				(width 0.1524)
				(type default)
			)
			(layer "F.SilkS")
		)
		(fp_line
			(start 1.234948 6.415024)
			(end -1.234948 6.415024)
			(stroke
				(width 0.1524)
				(type default)
			)
			(layer "F.SilkS")
		)
		(fp_line
			(start -1.234948 6.415024)
			(end -1.234948 -1.335024)
			(stroke
				(width 0.1524)
				(type default)
			)
			(layer "F.SilkS")
		)
		(fp_poly
			(pts
				(xy 0.508 -2.530348) (xy -0.508 -2.530348) (xy 0 -1.514348)
			)
			(stroke
				(width 0)
				(type default)
			)
			(fill yes)
			(layer "F.SilkS")
		)
		(fp_line
			(start 1.234948 -1.335024)
			(end 1.234948 6.415024)
			(stroke
				(width 0.1)
				(type default)
			)
			(layer "F.Fab")
		)
		(fp_line
			(start -1.234948 -1.335024)
			(end 1.234948 -1.335024)
			(stroke
				(width 0.1)
				(type default)
			)
			(layer "F.Fab")
		)
		(fp_line
			(start 1.234948 6.415024)
			(end -1.234948 6.415024)
			(stroke
				(width 0.1)
				(type default)
			)
			(layer "F.Fab")
		)
		(fp_line
			(start -1.234948 6.415024)
			(end -1.234948 -1.335024)
			(stroke
				(width 0.1)
				(type default)
			)
			(layer "F.Fab")
		)
		(fp_poly
			(pts
				(xy 0.508 -2.530348) (xy -0.508 -2.530348) (xy 0 -1.514348)
			)
			(stroke
				(width 0)
				(type default)
			)
			(fill yes)
			(layer "F.Fab")
		)
		(fp_text user "3"
			(at -2.05867 4.826 0)
			(unlocked yes)
			(layer "F.SilkS")
			(effects
				(font
					(size 0.7874 0.5842)
					(thickness 0.1524)
				)
				(justify left)
			)
		)
		(fp_text user "1"
			(at -0.00127 -0.954024 0)
			(unlocked yes)
			(layer "B.SilkS")
			(effects
				(font
					(size 0.7874 0.5842)
					(thickness 0.1524)
				)
				(justify left mirror)
			)
		)
		(fp_text user "3"
			(at -0.00127 6.640576 0)
			(unlocked yes)
			(layer "B.SilkS")
			(effects
				(font
					(size 0.7874 0.5842)
					(thickness 0.1524)
				)
				(justify left mirror)
			)
		)
		(fp_text user "1"
			(at -0.00127 -0.954024 0)
			(unlocked yes)
			(layer "B.Fab")
			(effects
				(font
					(size 0.7874 0.5842)
					(thickness 0.1524)
				)
				(justify left mirror)
			)
		)
		(fp_text user "3"
			(at -0.00127 6.640576 0)
			(unlocked yes)
			(layer "B.Fab")
			(effects
				(font
					(size 0.7874 0.5842)
					(thickness 0.1524)
				)
				(justify left mirror)
			)
		)
		(fp_text user "3"
			(at -0.009652 6.5659 0)
			(unlocked yes)
			(layer "F.Fab")
			(effects
				(font
					(size 0.7874 0.5842)
					(thickness 0.1524)
				)
				(justify left)
			)
		)
		(pad "1" thru_hole rect
			(at 0 0)
			(size 1.6764 1.6764)
			(drill 1.1684)
			(layers "*.Cu" "*.Mask")
			(remove_unused_layers no)
			(net "FM_HSC_EN_BUSBAR")
			(clearance 0)
			(padstack
				(mode front_inner_back)
				(layer "Inner"
					(shape circle)
					(size 1.6764 1.6764)
					(clearance 0)
				)
				(layer "B.Cu"
					(shape rect)
					(size 1.6764 1.6764)
					(clearance 0)
				)
			)
		)
		(pad "2" thru_hole circle
			(at 0 2.54)
			(size 1.6764 1.6764)
			(drill 1.1684)
			(layers "*.Cu" "*.Mask")
			(remove_unused_layers no)
			(net "P52V_HS1_EN")
			(clearance 0)
		)
		(pad "3" thru_hole circle
			(at 0 5.08)
			(size 1.6764 1.6764)
			(drill 1.1684)
			(layers "*.Cu" "*.Mask")
			(remove_unused_layers no)
			(net "FM_HSC_EN_FUSE")
			(clearance 0)
		)
	)
	(footprint ""
		(layer "F.Cu")
		(at 146.431 -136.906 90)
		(property "Reference" "PC15"
			(at 6.06933 1.27 0)
			(unlocked yes)
			(layer "F.SilkS")
			(effects
				(font
					(size 0.7874 0.5842)
					(thickness 0.1524)
				)
				(justify left)
			)
		)
		(property "Value" ""
			(at 0 0 90)
			(layer "F.Fab")
			(effects
				(font
					(size 1.27 1.27)
				)
			)
		)
		(duplicate_pad_numbers_are_jumpers no)
		(fp_line
			(start 5.2578 2.499868)
			(end -5.2578 2.499868)
			(stroke
				(width 0.1524)
				(type default)
			)
			(layer "F.SilkS")
		)
		(fp_circle
			(center 0 2.500122)
			(end 0 7.758176)
			(stroke
				(width 0.1524)
				(type default)
			)
			(fill no)
			(layer "F.SilkS")
		)
		(fp_poly
			(pts
				(arc
					(start 5.2578 2.499868)
					(mid 0 7.757922)
					(end -5.2578 2.499868)
				)
			)
			(stroke
				(width 0)
				(type default)
			)
			(fill yes)
			(layer "F.SilkS")
		)
		(fp_circle
			(center 0 2.500122)
			(end 0 7.758176)
			(stroke
				(width 0.1)
				(type default)
			)
			(fill no)
			(layer "F.Fab")
		)
		(pad "1" thru_hole rect
			(at 0 0)
			(size 1.5748 1.5748)
			(drill 1.0668)
			(layers "*.Cu" "*.Mask")
			(remove_unused_layers no)
			(net "P52V_HS_FILTER")
			(clearance 0)
			(padstack
				(mode front_inner_back)
				(layer "Inner"
					(shape circle)
					(size 1.5748 1.5748)
					(clearance 0)
				)
				(layer "B.Cu"
					(shape rect)
					(size 1.5748 1.5748)
					(clearance 0)
				)
			)
		)
		(pad "2" thru_hole circle
			(at 0 4.99999)
			(size 1.5748 1.5748)
			(drill 1.0668)
			(layers "*.Cu" "*.Mask")
			(remove_unused_layers no)
			(net "GND")
			(clearance 0)
		)
	)
	(footprint ""
		(layer "F.Cu")
		(at 220.218 -95.504 -90)
		(property "Reference" "C27"
			(at 0 0 270)
			(layer "F.SilkS")
			(hide yes)
			(effects
				(font
					(size 1.27 1.27)
				)
			)
		)
		(property "Value" ""
			(at 0 0 270)
			(layer "F.Fab")
			(effects
				(font
					(size 1.27 1.27)
				)
			)
		)
		(duplicate_pad_numbers_are_jumpers no)
		(fp_line
			(start -2.2098 0.9398)
			(end -2.2098 -0.9398)
			(stroke
				(width 0.1524)
				(type default)
			)
			(layer "F.SilkS")
		)
		(fp_line
			(start 2.2098 0.9398)
			(end -2.2098 0.9398)
			(stroke
				(width 0.1524)
				(type default)
			)
			(layer "F.SilkS")
		)
		(fp_line
			(start -2.2098 -0.9398)
			(end 2.2098 -0.9398)
			(stroke
				(width 0.1524)
				(type default)
			)
			(layer "F.SilkS")
		)
		(fp_line
			(start 2.2098 -0.9398)
			(end 2.2098 0.9398)
			(stroke
				(width 0.1524)
				(type default)
			)
			(layer "F.SilkS")
		)
		(fp_line
			(start -1.700022 0.899922)
			(end -1.700022 -0.899922)
			(stroke
				(width 0.1)
				(type default)
			)
			(layer "F.Fab")
		)
		(fp_line
			(start 1.700022 0.899922)
			(end -1.700022 0.899922)
			(stroke
				(width 0.1)
				(type default)
			)
			(layer "F.Fab")
		)
		(fp_line
			(start -1.700022 -0.899922)
			(end 1.700022 -0.899922)
			(stroke
				(width 0.1)
				(type default)
			)
			(layer "F.Fab")
		)
		(fp_line
			(start 1.700022 -0.899922)
			(end 1.700022 0.899922)
			(stroke
				(width 0.1)
				(type default)
			)
			(layer "F.Fab")
		)
		(pad "1" smd rect
			(at -1.4732 0 90)
			(size 1.1684 1.5748)
			(layers "F.Cu" "F.Mask" "F.Paste")
			(net "P52V_HS")
		)
		(pad "2" smd rect
			(at 1.4732 0 90)
			(size 1.1684 1.5748)
			(layers "F.Cu" "F.Mask" "F.Paste")
			(net "GND")
		)
	)
)
